# T6G (Grand Teton) — schematic netlist excerpt (pin names and nets, part order shuffled) for the footprints in the layout excerpt that follows; sources: Cadence DE-HDL packaged netlist, KiCad conversion of 04192023_DAF0TMB3IC0_F0TG_MB_C_brd_V02_OCP.brd

Q56  MOSFET_NCH_1D3S  PSMNR58-30YLH IC  pkg SOT1023  page 188
  \1\  = P3V3
  \2\  = P3V3
  \3\  = P3V3
  \4\  = SW_P3V3_EN_ISO_R
  \5\  = P3V3_AUX

C1873  Q_CAP  0.1UF 25V 10% X7R  pkg 0402  page 144 : A = P3V3_AUX ; B = GND

(kicad_pcb
	(version 20260206)
	(generator "pcbnew")
	(generator_version "10.0")
	(general
		(thickness 1.6)
		(legacy_teardrops no)
	)
	(paper "A4")
	(title_block
		(title "04192023_DAF0TMB3IC0_F0TG_MB_C_brd_V02_OCP.brd")
		(comment 1 "Grand Teton / footprints 4492-4493 of 8354")
	)
	(layers
		(0 "F.Cu" signal "TOP")
		(4 "In1.Cu" signal "GND")
		(6 "In2.Cu" signal "IN1")
		(8 "In3.Cu" signal "GND1")
		(10 "In4.Cu" signal "IN2")
		(12 "In5.Cu" signal "GND2")
		(14 "In6.Cu" signal "IN3")
		(16 "In7.Cu" signal "GND3")
		(18 "In8.Cu" signal "VCC")
		(20 "In9.Cu" signal "VCC1")
		(22 "In10.Cu" signal "GND4")
		(24 "In11.Cu" signal "IN4")
		(26 "In12.Cu" signal "GND5")
		(28 "In13.Cu" signal "IN5")
		(30 "In14.Cu" signal "GND6")
		(32 "In15.Cu" signal "IN6")
		(34 "In16.Cu" signal "GND7")
		(2 "B.Cu" signal "BOTTOM")
		(9 "F.Adhes" user "F.Adhesive")
		(11 "B.Adhes" user "B.Adhesive")
		(13 "F.Paste" user "Package Geometry/Pastemask Top")
		(15 "B.Paste" user "Package Geometry/Pastemask Bottom")
		(5 "F.SilkS" user "Ref Des/Silkscreen Top")
		(7 "B.SilkS" user "Ref Des/Silkscreen Bottom")
		(1 "F.Mask" user "Board Geometry/Soldermask Top")
		(3 "B.Mask" user "Board Geometry/Soldermask Bottom")
		(17 "Dwgs.User" user "User.Drawings")
		(19 "Cmts.User" user "User.Comments")
		(21 "Eco1.User" user "User.Eco1")
		(23 "Eco2.User" user "User.Eco2")
		(25 "Edge.Cuts" user "Board Geometry/Outline")
		(27 "Margin" user)
		(31 "F.CrtYd" user "Package Geometry/Place Bound Top")
		(29 "B.CrtYd" user "Package Geometry/Place Bound Bottom")
		(35 "F.Fab" user "Ref Des/Assembly Top")
		(33 "B.Fab" user "Ref Des/Assembly Bottom")
	)
	(footprint ""
		(layer "F.Cu")
		(at 441.470034 -69.861176 -90)
		(property "Reference" "Q56"
			(at -1.4478 3.592576 90)
			(unlocked yes)
			(layer "F.SilkS")
			(effects
				(font
					(size 0.7874 0.5842)
					(thickness 0.1524)
				)
			)
		)
		(property "Value" ""
			(at 0 0 270)
			(layer "F.Fab")
			(effects
				(font
					(size 1.27 1.27)
				)
			)
		)
		(duplicate_pad_numbers_are_jumpers no)
		(fp_line
			(start -2.350008 2.649982)
			(end -2.350008 2.413)
			(stroke
				(width 0.1524)
				(type default)
			)
			(layer "F.SilkS")
		)
		(fp_line
			(start 2.350008 2.649982)
			(end -2.350008 2.649982)
			(stroke
				(width 0.1524)
				(type default)
			)
			(layer "F.SilkS")
		)
		(fp_line
			(start 2.350008 2.4892)
			(end 2.350008 2.649982)
			(stroke
				(width 0.1524)
				(type default)
			)
			(layer "F.SilkS")
		)
		(fp_line
			(start -2.350008 -2.4384)
			(end -2.350008 -2.649982)
			(stroke
				(width 0.1524)
				(type default)
			)
			(layer "F.SilkS")
		)
		(fp_line
			(start -2.350008 -2.649982)
			(end 2.350008 -2.649982)
			(stroke
				(width 0.1524)
				(type default)
			)
			(layer "F.SilkS")
		)
		(fp_line
			(start 2.350008 -2.649982)
			(end 2.350008 -2.4892)
			(stroke
				(width 0.1524)
				(type default)
			)
			(layer "F.SilkS")
		)
		(fp_poly
			(pts
				(xy -2.58699 -3.70967) (xy -3.00609 -2.66827) (xy -3.38709 -3.70967)
			)
			(stroke
				(width 0)
				(type default)
			)
			(fill yes)
			(layer "F.SilkS")
		)
		(fp_line
			(start -2.350008 2.649982)
			(end -2.350008 -2.649982)
			(stroke
				(width 0.1)
				(type default)
			)
			(layer "F.Fab")
		)
		(fp_line
			(start 2.350008 2.649982)
			(end -2.350008 2.649982)
			(stroke
				(width 0.1)
				(type default)
			)
			(layer "F.Fab")
		)
		(fp_line
			(start -2.350008 -2.649982)
			(end 2.350008 -2.649982)
			(stroke
				(width 0.1)
				(type default)
			)
			(layer "F.Fab")
		)
		(fp_line
			(start 2.350008 -2.649982)
			(end 2.350008 2.649982)
			(stroke
				(width 0.1)
				(type default)
			)
			(layer "F.Fab")
		)
		(fp_poly
			(pts
				(xy -3.717544 -1.905) (xy -4.758944 -2.3241) (xy -4.758944 -1.524)
			)
			(stroke
				(width 0)
				(type default)
			)
			(fill yes)
			(layer "F.Fab")
		)
		(pad "1" smd rect
			(at -2.999994 -1.905 180)
			(size 0.7112 1.1684)
			(layers "F.Cu" "F.Mask" "F.Paste")
			(net "P3V3")
		)
		(pad "2" smd rect
			(at -2.999994 -0.635 180)
			(size 0.7112 1.1684)
			(layers "F.Cu" "F.Mask" "F.Paste")
			(net "P3V3")
		)
		(pad "3" smd rect
			(at -2.999994 0.635 180)
			(size 0.7112 1.1684)
			(layers "F.Cu" "F.Mask" "F.Paste")
			(net "P3V3")
		)
		(pad "4" smd rect
			(at -2.999994 1.905 180)
			(size 0.7112 1.1684)
			(layers "F.Cu" "F.Mask" "F.Paste")
			(net "SW_P3V3_EN_ISO_R")
		)
		(pad "5" smd circle
			(at 0.925068 0 180)
			(size 0 0)
			(layers "F.Cu" "F.Mask" "F.Paste")
			(net "P3V3_AUX")
		)
		(zone
			(layer "F.Cu")
			(hatch none 0.5)
			(connect_pads
				(clearance 0)
			)
			(min_thickness 0.25)
			(keepout
				(tracks not_allowed)
				(vias allowed)
				(pads allowed)
				(copperpour not_allowed)
				(footprints allowed)
			)
			(placement
				(enabled no)
				(sheetname "")
			)
			(fill
				(thermal_gap 0.5)
				(thermal_bridge_width 0.5)
				(island_removal_mode 0)
			)
			(polygon
				(pts
					(xy 443.629034 -71.308976) (xy 439.311034 -71.308976) (xy 438.828434 -71.308976) (xy 438.828434 -72.210676)
					(xy 444.111634 -72.210676) (xy 444.111634 -71.571104) (xy 443.849506 -71.308976)
				)
			)
		)
	)
	(footprint ""
		(layer "F.Cu")
		(at 156.30779 -103.738934 90)
		(property "Reference" "C1873"
			(at 0 0 90)
			(layer "F.SilkS")
			(hide yes)
			(effects
				(font
					(size 1.27 1.27)
				)
			)
		)
		(property "Value" ""
			(at 0 0 90)
			(layer "F.Fab")
			(effects
				(font
					(size 1.27 1.27)
				)
			)
		)
		(duplicate_pad_numbers_are_jumpers no)
		(fp_line
			(start 0.7874 -0.4064)
			(end 0.7874 0.4064)
			(stroke
				(width 0.1524)
				(type default)
			)
			(layer "F.SilkS")
		)
		(fp_line
			(start -0.7874 -0.4064)
			(end 0.7874 -0.4064)
			(stroke
				(width 0.1524)
				(type default)
			)
			(layer "F.SilkS")
		)
		(fp_line
			(start 0.7874 0.4064)
			(end -0.7874 0.4064)
			(stroke
				(width 0.1524)
				(type default)
			)
			(layer "F.SilkS")
		)
		(fp_line
			(start -0.7874 0.4064)
			(end -0.7874 -0.4064)
			(stroke
				(width 0.1524)
				(type default)
			)
			(layer "F.SilkS")
		)
		(fp_line
			(start -0.12065 -0.305054)
			(end -0.12065 -0.2794)
			(stroke
				(width 0.1)
				(type default)
			)
			(layer "F.Fab")
		)
		(fp_line
			(start -0.67945 -0.305054)
			(end -0.12065 -0.305054)
			(stroke
				(width 0.1)
				(type default)
			)
			(layer "F.Fab")
		)
		(fp_line
			(start 0.67945 -0.3048)
			(end 0.67945 0.3048)
			(stroke
				(width 0.1)
				(type default)
			)
			(layer "F.Fab")
		)
		(fp_line
			(start 0.12065 -0.3048)
			(end 0.67945 -0.3048)
			(stroke
				(width 0.1)
				(type default)
			)
			(layer "F.Fab")
		)
		(fp_line
			(start 0.12065 -0.2794)
			(end 0.12065 -0.3048)
			(stroke
				(width 0.1)
				(type default)
			)
			(layer "F.Fab")
		)
		(fp_line
			(start -0.12065 -0.2794)
			(end 0.12065 -0.2794)
			(stroke
				(width 0.1)
				(type default)
			)
			(layer "F.Fab")
		)
		(fp_line
			(start 0.120396 0.2794)
			(end -0.12065 0.2794)
			(stroke
				(width 0.1)
				(type default)
			)
			(layer "F.Fab")
		)
		(fp_line
			(start -0.12065 0.2794)
			(end -0.12065 0.3048)
			(stroke
				(width 0.1)
				(type default)
			)
			(layer "F.Fab")
		)
		(fp_line
			(start 0.67945 0.3048)
			(end 0.120396 0.3048)
			(stroke
				(width 0.1)
				(type default)
			)
			(layer "F.Fab")
		)
		(fp_line
			(start 0.120396 0.3048)
			(end 0.120396 0.2794)
			(stroke
				(width 0.1)
				(type default)
			)
			(layer "F.Fab")
		)
		(fp_line
			(start -0.12065 0.3048)
			(end -0.67945 0.3048)
			(stroke
				(width 0.1)
				(type default)
			)
			(layer "F.Fab")
		)
		(fp_line
			(start -0.67945 0.3048)
			(end -0.67945 -0.305054)
			(stroke
				(width 0.1)
				(type default)
			)
			(layer "F.Fab")
		)
		(pad "1" smd circle
			(at -0.40005 0 90)
			(size 0 0)
			(layers "F.Cu" "F.Mask" "F.Paste")
			(net "P3V3_AUX")
		)
		(pad "2" smd circle
			(at 0.40005 0 90)
			(size 0 0)
			(layers "F.Cu" "F.Mask" "F.Paste")
			(net "GND")
		)
	)
)
